# T6G (Grand Teton) — schematic netlist excerpt (pin names and nets, part order shuffled) for the footprints in the layout excerpt that follows; sources: Cadence DE-HDL packaged netlist, KiCad conversion of 04192023_DAF0TMB3IC0_F0TG_MB_C_brd_V02_OCP.brd

R3752  Q_RES  0 5% CHIP  pkg 0402LF  page 236 : A = E1S_0_P3V3_ADC_ALERT_R ; B = E1S_0_P3V3_P12V_ADC_R_ALERT
C2375  Q_CAP  22UF 4V 20% X6S  pkg C0402  page 73 : A = PVDDCR_CPU1_P1 ; B = GND

(kicad_pcb
	(version 20260206)
	(generator "pcbnew")
	(generator_version "10.0")
	(general
		(thickness 1.6)
		(legacy_teardrops no)
	)
	(paper "A4")
	(title_block
		(title "04192023_DAF0TMB3IC0_F0TG_MB_C_brd_V02_OCP.brd")
		(comment 1 "Grand Teton / footprints 5677-5678 of 8354")
	)
	(layers
		(0 "F.Cu" signal "TOP")
		(4 "In1.Cu" signal "GND")
		(6 "In2.Cu" signal "IN1")
		(8 "In3.Cu" signal "GND1")
		(10 "In4.Cu" signal "IN2")
		(12 "In5.Cu" signal "GND2")
		(14 "In6.Cu" signal "IN3")
		(16 "In7.Cu" signal "GND3")
		(18 "In8.Cu" signal "VCC")
		(20 "In9.Cu" signal "VCC1")
		(22 "In10.Cu" signal "GND4")
		(24 "In11.Cu" signal "IN4")
		(26 "In12.Cu" signal "GND5")
		(28 "In13.Cu" signal "IN5")
		(30 "In14.Cu" signal "GND6")
		(32 "In15.Cu" signal "IN6")
		(34 "In16.Cu" signal "GND7")
		(2 "B.Cu" signal "BOTTOM")
		(9 "F.Adhes" user "F.Adhesive")
		(11 "B.Adhes" user "B.Adhesive")
		(13 "F.Paste" user "Package Geometry/Pastemask Top")
		(15 "B.Paste" user "Package Geometry/Pastemask Bottom")
		(5 "F.SilkS" user "Ref Des/Silkscreen Top")
		(7 "B.SilkS" user "Ref Des/Silkscreen Bottom")
		(1 "F.Mask" user "Board Geometry/Soldermask Top")
		(3 "B.Mask" user "Board Geometry/Soldermask Bottom")
		(17 "Dwgs.User" user "User.Drawings")
		(19 "Cmts.User" user "User.Comments")
		(21 "Eco1.User" user "User.Eco1")
		(23 "Eco2.User" user "User.Eco2")
		(25 "Edge.Cuts" user "Board Geometry/Outline")
		(27 "Margin" user)
		(31 "F.CrtYd" user "Package Geometry/Place Bound Top")
		(29 "B.CrtYd" user "Package Geometry/Place Bound Bottom")
		(35 "F.Fab" user "Ref Des/Assembly Top")
		(33 "B.Fab" user "Ref Des/Assembly Bottom")
	)
	(footprint ""
		(layer "B.Cu")
		(at 118.277386 -268.418564)
		(property "Reference" "C2375"
			(at 0 0 0)
			(layer "B.SilkS")
			(hide yes)
			(effects
				(font
					(size 1.27 1.27)
				)
				(justify mirror)
			)
		)
		(property "Value" ""
			(at 0 0 0)
			(layer "B.Fab")
			(effects
				(font
					(size 1.27 1.27)
				)
				(justify mirror)
			)
		)
		(duplicate_pad_numbers_are_jumpers no)
		(fp_line
			(start -0.7874 -0.4064)
			(end -0.7874 0.4064)
			(stroke
				(width 0.1524)
				(type default)
			)
			(layer "B.SilkS")
		)
		(fp_line
			(start -0.7874 0.4064)
			(end 0.7874 0.4064)
			(stroke
				(width 0.1524)
				(type default)
			)
			(layer "B.SilkS")
		)
		(fp_line
			(start 0.7874 -0.4064)
			(end -0.7874 -0.4064)
			(stroke
				(width 0.1524)
				(type default)
			)
			(layer "B.SilkS")
		)
		(fp_line
			(start 0.7874 0.4064)
			(end 0.7874 -0.4064)
			(stroke
				(width 0.1524)
				(type default)
			)
			(layer "B.SilkS")
		)
		(fp_line
			(start -0.67945 -0.3048)
			(end -0.67945 0.3048)
			(stroke
				(width 0.1)
				(type default)
			)
			(layer "B.Fab")
		)
		(fp_line
			(start -0.67945 0.3048)
			(end -0.120396 0.3048)
			(stroke
				(width 0.1)
				(type default)
			)
			(layer "B.Fab")
		)
		(fp_line
			(start -0.12065 -0.3048)
			(end -0.67945 -0.3048)
			(stroke
				(width 0.1)
				(type default)
			)
			(layer "B.Fab")
		)
		(fp_line
			(start -0.12065 -0.2794)
			(end -0.12065 -0.3048)
			(stroke
				(width 0.1)
				(type default)
			)
			(layer "B.Fab")
		)
		(fp_line
			(start -0.120396 0.2794)
			(end 0.12065 0.2794)
			(stroke
				(width 0.1)
				(type default)
			)
			(layer "B.Fab")
		)
		(fp_line
			(start -0.120396 0.3048)
			(end -0.120396 0.2794)
			(stroke
				(width 0.1)
				(type default)
			)
			(layer "B.Fab")
		)
		(fp_line
			(start 0.12065 -0.305054)
			(end 0.12065 -0.2794)
			(stroke
				(width 0.1)
				(type default)
			)
			(layer "B.Fab")
		)
		(fp_line
			(start 0.12065 -0.2794)
			(end -0.12065 -0.2794)
			(stroke
				(width 0.1)
				(type default)
			)
			(layer "B.Fab")
		)
		(fp_line
			(start 0.12065 0.2794)
			(end 0.12065 0.3048)
			(stroke
				(width 0.1)
				(type default)
			)
			(layer "B.Fab")
		)
		(fp_line
			(start 0.12065 0.3048)
			(end 0.67945 0.3048)
			(stroke
				(width 0.1)
				(type default)
			)
			(layer "B.Fab")
		)
		(fp_line
			(start 0.67945 -0.305054)
			(end 0.12065 -0.305054)
			(stroke
				(width 0.1)
				(type default)
			)
			(layer "B.Fab")
		)
		(fp_line
			(start 0.67945 0.3048)
			(end 0.67945 -0.305054)
			(stroke
				(width 0.1)
				(type default)
			)
			(layer "B.Fab")
		)
		(pad "1" smd circle
			(at 0.40005 0 180)
			(size 0 0)
			(layers "B.Cu" "B.Mask" "B.Paste")
			(net "PVDDCR_CPU1_P1")
		)
		(pad "2" smd circle
			(at -0.40005 0 180)
			(size 0 0)
			(layers "B.Cu" "B.Mask" "B.Paste")
			(net "GND")
		)
	)
	(footprint ""
		(layer "B.Cu")
		(at 211.69503 -57.078372 -90)
		(property "Reference" "R3752"
			(at 0 0 90)
			(layer "B.SilkS")
			(hide yes)
			(effects
				(font
					(size 1.27 1.27)
				)
				(justify mirror)
			)
		)
		(property "Value" ""
			(at 0 0 90)
			(layer "B.Fab")
			(effects
				(font
					(size 1.27 1.27)
				)
				(justify mirror)
			)
		)
		(duplicate_pad_numbers_are_jumpers no)
		(fp_line
			(start -0.7874 0.4064)
			(end 0.7874 0.4064)
			(stroke
				(width 0.1524)
				(type default)
			)
			(layer "B.SilkS")
		)
		(fp_line
			(start 0.7874 0.4064)
			(end 0.7874 -0.4064)
			(stroke
				(width 0.1524)
				(type default)
			)
			(layer "B.SilkS")
		)
		(fp_line
			(start -0.7874 -0.4064)
			(end -0.7874 0.4064)
			(stroke
				(width 0.1524)
				(type default)
			)
			(layer "B.SilkS")
		)
		(fp_line
			(start 0.7874 -0.4064)
			(end -0.7874 -0.4064)
			(stroke
				(width 0.1524)
				(type default)
			)
			(layer "B.SilkS")
		)
		(fp_line
			(start -0.67945 0.3048)
			(end -0.120396 0.3048)
			(stroke
				(width 0.1)
				(type default)
			)
			(layer "B.Fab")
		)
		(fp_line
			(start -0.120396 0.3048)
			(end -0.120396 0.2794)
			(stroke
				(width 0.1)
				(type default)
			)
			(layer "B.Fab")
		)
		(fp_line
			(start 0.12065 0.3048)
			(end 0.67945 0.3048)
			(stroke
				(width 0.1)
				(type default)
			)
			(layer "B.Fab")
		)
		(fp_line
			(start 0.67945 0.3048)
			(end 0.67945 -0.305054)
			(stroke
				(width 0.1)
				(type default)
			)
			(layer "B.Fab")
		)
		(fp_line
			(start -0.120396 0.2794)
			(end 0.12065 0.2794)
			(stroke
				(width 0.1)
				(type default)
			)
			(layer "B.Fab")
		)
		(fp_line
			(start 0.12065 0.2794)
			(end 0.12065 0.3048)
			(stroke
				(width 0.1)
				(type default)
			)
			(layer "B.Fab")
		)
		(fp_line
			(start -0.12065 -0.2794)
			(end -0.12065 -0.3048)
			(stroke
				(width 0.1)
				(type default)
			)
			(layer "B.Fab")
		)
		(fp_line
			(start 0.12065 -0.2794)
			(end -0.12065 -0.2794)
			(stroke
				(width 0.1)
				(type default)
			)
			(layer "B.Fab")
		)
		(fp_line
			(start -0.67945 -0.3048)
			(end -0.67945 0.3048)
			(stroke
				(width 0.1)
				(type default)
			)
			(layer "B.Fab")
		)
		(fp_line
			(start -0.12065 -0.3048)
			(end -0.67945 -0.3048)
			(stroke
				(width 0.1)
				(type default)
			)
			(layer "B.Fab")
		)
		(fp_line
			(start 0.12065 -0.305054)
			(end 0.12065 -0.2794)
			(stroke
				(width 0.1)
				(type default)
			)
			(layer "B.Fab")
		)
		(fp_line
			(start 0.67945 -0.305054)
			(end 0.12065 -0.305054)
			(stroke
				(width 0.1)
				(type default)
			)
			(layer "B.Fab")
		)
		(pad "1" smd circle
			(at 0.40005 0 90)
			(size 0 0)
			(layers "B.Cu" "B.Mask" "B.Paste")
			(net "E1S_0_P3V3_ADC_ALERT_R")
		)
		(pad "2" smd circle
			(at -0.40005 0 90)
			(size 0 0)
			(layers "B.Cu" "B.Mask" "B.Paste")
			(net "E1S_0_P3V3_P12V_ADC_R_ALERT")
		)
	)
)
